# S9S_MB_2U (Grand Teton) — schematic netlist excerpt (pin names and nets, part order shuffled) for the footprints in the layout excerpt that follows; sources: Cadence DE-HDL packaged netlist, KiCad conversion of 03242023_DA0F0TMBIJ0_F0T_Motherboard_J_brd_V01_OCP.brd

R335  Q_RES  1K 1% EMPTY  pkg 0402LF  page 127 : A = P3V3_AUX ; B = PD_PIROM_CPU0_ADDR0
C263  Q_CAP  10UF 6.3V 20% X6S  pkg C0402  page 77 : A = PVCCIN_CPU1 ; B = GND

(kicad_pcb
	(version 20260206)
	(generator "pcbnew")
	(generator_version "10.0")
	(general
		(thickness 1.6)
		(legacy_teardrops no)
	)
	(paper "A4")
	(title_block
		(title "03242023_DA0F0TMBIJ0_F0T_Motherboard_J_brd_V01_OCP.brd")
		(comment 1 "Grand Teton / footprints 3735-3736 of 6105")
	)
	(layers
		(0 "F.Cu" signal "TOP")
		(4 "In1.Cu" signal "GND")
		(6 "In2.Cu" signal "IN1")
		(8 "In3.Cu" signal "GND1")
		(10 "In4.Cu" signal "IN2")
		(12 "In5.Cu" signal "GND2")
		(14 "In6.Cu" signal "IN3")
		(16 "In7.Cu" signal "GND3")
		(18 "In8.Cu" signal "VCC")
		(20 "In9.Cu" signal "VCC1")
		(22 "In10.Cu" signal "GND4")
		(24 "In11.Cu" signal "IN4")
		(26 "In12.Cu" signal "GND5")
		(28 "In13.Cu" signal "IN5")
		(30 "In14.Cu" signal "GND6")
		(32 "In15.Cu" signal "IN6")
		(34 "In16.Cu" signal "GND7")
		(2 "B.Cu" signal "BOTTOM")
		(9 "F.Adhes" user "F.Adhesive")
		(11 "B.Adhes" user "B.Adhesive")
		(13 "F.Paste" user "Package Geometry/Pastemask Top")
		(15 "B.Paste" user "Package Geometry/Pastemask Bottom")
		(5 "F.SilkS" user "Ref Des/Silkscreen Top")
		(7 "B.SilkS" user "Ref Des/Silkscreen Bottom")
		(1 "F.Mask" user "Board Geometry/Soldermask Top")
		(3 "B.Mask" user "Board Geometry/Soldermask Bottom")
		(17 "Dwgs.User" user "User.Drawings")
		(19 "Cmts.User" user "User.Comments")
		(21 "Eco1.User" user "User.Eco1")
		(23 "Eco2.User" user "User.Eco2")
		(25 "Edge.Cuts" user "Board Geometry/Outline")
		(27 "Margin" user)
		(31 "F.CrtYd" user "Package Geometry/Place Bound Top")
		(29 "B.CrtYd" user "Package Geometry/Place Bound Bottom")
		(35 "F.Fab" user "Ref Des/Assembly Top")
		(33 "B.Fab" user "Ref Des/Assembly Bottom")
	)
	(footprint ""
		(layer "F.Cu")
		(at 406.124664 -363.008926 180)
		(property "Reference" "R335"
			(at 0 0 180)
			(layer "F.SilkS")
			(hide yes)
			(effects
				(font
					(size 1.27 1.27)
				)
			)
		)
		(property "Value" ""
			(at 0 0 180)
			(layer "F.Fab")
			(effects
				(font
					(size 1.27 1.27)
				)
			)
		)
		(duplicate_pad_numbers_are_jumpers no)
		(fp_line
			(start 0.7874 0.4064)
			(end -0.7874 0.4064)
			(stroke
				(width 0.1524)
				(type default)
			)
			(layer "F.SilkS")
		)
		(fp_line
			(start 0.7874 -0.4064)
			(end 0.7874 0.4064)
			(stroke
				(width 0.1524)
				(type default)
			)
			(layer "F.SilkS")
		)
		(fp_line
			(start -0.7874 0.4064)
			(end -0.7874 -0.4064)
			(stroke
				(width 0.1524)
				(type default)
			)
			(layer "F.SilkS")
		)
		(fp_line
			(start -0.7874 -0.4064)
			(end 0.7874 -0.4064)
			(stroke
				(width 0.1524)
				(type default)
			)
			(layer "F.SilkS")
		)
		(fp_line
			(start 0.67945 0.3048)
			(end 0.120396 0.3048)
			(stroke
				(width 0.1)
				(type default)
			)
			(layer "F.Fab")
		)
		(fp_line
			(start 0.67945 -0.3048)
			(end 0.67945 0.3048)
			(stroke
				(width 0.1)
				(type default)
			)
			(layer "F.Fab")
		)
		(fp_line
			(start 0.12065 -0.2794)
			(end 0.12065 -0.3048)
			(stroke
				(width 0.1)
				(type default)
			)
			(layer "F.Fab")
		)
		(fp_line
			(start 0.12065 -0.3048)
			(end 0.67945 -0.3048)
			(stroke
				(width 0.1)
				(type default)
			)
			(layer "F.Fab")
		)
		(fp_line
			(start 0.120396 0.3048)
			(end 0.120396 0.2794)
			(stroke
				(width 0.1)
				(type default)
			)
			(layer "F.Fab")
		)
		(fp_line
			(start 0.120396 0.2794)
			(end -0.12065 0.2794)
			(stroke
				(width 0.1)
				(type default)
			)
			(layer "F.Fab")
		)
		(fp_line
			(start -0.12065 0.3048)
			(end -0.67945 0.3048)
			(stroke
				(width 0.1)
				(type default)
			)
			(layer "F.Fab")
		)
		(fp_line
			(start -0.12065 0.2794)
			(end -0.12065 0.3048)
			(stroke
				(width 0.1)
				(type default)
			)
			(layer "F.Fab")
		)
		(fp_line
			(start -0.12065 -0.2794)
			(end 0.12065 -0.2794)
			(stroke
				(width 0.1)
				(type default)
			)
			(layer "F.Fab")
		)
		(fp_line
			(start -0.12065 -0.305054)
			(end -0.12065 -0.2794)
			(stroke
				(width 0.1)
				(type default)
			)
			(layer "F.Fab")
		)
		(fp_line
			(start -0.67945 0.3048)
			(end -0.67945 -0.305054)
			(stroke
				(width 0.1)
				(type default)
			)
			(layer "F.Fab")
		)
		(fp_line
			(start -0.67945 -0.305054)
			(end -0.12065 -0.305054)
			(stroke
				(width 0.1)
				(type default)
			)
			(layer "F.Fab")
		)
		(pad "1" smd circle
			(at -0.40005 0 180)
			(size 0 0)
			(layers "F.Cu" "F.Mask" "F.Paste")
			(net "P3V3_AUX")
		)
		(pad "2" smd circle
			(at 0.40005 0 180)
			(size 0 0)
			(layers "F.Cu" "F.Mask" "F.Paste")
			(net "PD_PIROM_CPU0_ADDR0")
		)
	)
	(footprint ""
		(layer "F.Cu")
		(at 118.542816 -251.375672 90)
		(property "Reference" "C263"
			(at 0 0 90)
			(layer "F.SilkS")
			(hide yes)
			(effects
				(font
					(size 1.27 1.27)
				)
			)
		)
		(property "Value" ""
			(at 0 0 90)
			(layer "F.Fab")
			(effects
				(font
					(size 1.27 1.27)
				)
			)
		)
		(duplicate_pad_numbers_are_jumpers no)
		(fp_line
			(start 0.7874 -0.4064)
			(end 0.7874 0.4064)
			(stroke
				(width 0.1524)
				(type default)
			)
			(layer "F.SilkS")
		)
		(fp_line
			(start -0.7874 -0.4064)
			(end 0.7874 -0.4064)
			(stroke
				(width 0.1524)
				(type default)
			)
			(layer "F.SilkS")
		)
		(fp_line
			(start 0.7874 0.4064)
			(end -0.7874 0.4064)
			(stroke
				(width 0.1524)
				(type default)
			)
			(layer "F.SilkS")
		)
		(fp_line
			(start -0.7874 0.4064)
			(end -0.7874 -0.4064)
			(stroke
				(width 0.1524)
				(type default)
			)
			(layer "F.SilkS")
		)
		(fp_line
			(start -0.12065 -0.305054)
			(end -0.12065 -0.2794)
			(stroke
				(width 0.1)
				(type default)
			)
			(layer "F.Fab")
		)
		(fp_line
			(start -0.67945 -0.305054)
			(end -0.12065 -0.305054)
			(stroke
				(width 0.1)
				(type default)
			)
			(layer "F.Fab")
		)
		(fp_line
			(start 0.67945 -0.3048)
			(end 0.67945 0.3048)
			(stroke
				(width 0.1)
				(type default)
			)
			(layer "F.Fab")
		)
		(fp_line
			(start 0.12065 -0.3048)
			(end 0.67945 -0.3048)
			(stroke
				(width 0.1)
				(type default)
			)
			(layer "F.Fab")
		)
		(fp_line
			(start 0.12065 -0.2794)
			(end 0.12065 -0.3048)
			(stroke
				(width 0.1)
				(type default)
			)
			(layer "F.Fab")
		)
		(fp_line
			(start -0.12065 -0.2794)
			(end 0.12065 -0.2794)
			(stroke
				(width 0.1)
				(type default)
			)
			(layer "F.Fab")
		)
		(fp_line
			(start 0.120396 0.2794)
			(end -0.12065 0.2794)
			(stroke
				(width 0.1)
				(type default)
			)
			(layer "F.Fab")
		)
		(fp_line
			(start -0.12065 0.2794)
			(end -0.12065 0.3048)
			(stroke
				(width 0.1)
				(type default)
			)
			(layer "F.Fab")
		)
		(fp_line
			(start 0.67945 0.3048)
			(end 0.120396 0.3048)
			(stroke
				(width 0.1)
				(type default)
			)
			(layer "F.Fab")
		)
		(fp_line
			(start 0.120396 0.3048)
			(end 0.120396 0.2794)
			(stroke
				(width 0.1)
				(type default)
			)
			(layer "F.Fab")
		)
		(fp_line
			(start -0.12065 0.3048)
			(end -0.67945 0.3048)
			(stroke
				(width 0.1)
				(type default)
			)
			(layer "F.Fab")
		)
		(fp_line
			(start -0.67945 0.3048)
			(end -0.67945 -0.305054)
			(stroke
				(width 0.1)
				(type default)
			)
			(layer "F.Fab")
		)
		(pad "1" smd circle
			(at -0.40005 0 90)
			(size 0 0)
			(layers "F.Cu" "F.Mask" "F.Paste")
			(net "PVCCIN_CPU1")
		)
		(pad "2" smd circle
			(at 0.40005 0 90)
			(size 0 0)
			(layers "F.Cu" "F.Mask" "F.Paste")
			(net "GND")
		)
	)
)
